(kicad_pcb
	(version 20240108)
	(generator "pcbnew")
	(generator_version "8.0")
	(general
		(thickness 1.62)
		(legacy_teardrops no)
	)
	(paper "A4")
	(title_block
		(title "Jetson Orin Baseboard")
		(date "2025-03-12")
		(rev "1.3.4")
		(company "Antmicro Ltd")
		(comment 1 "www.antmicro.com")
		(comment 9 "footprints 140-143 of 677")
	)
	(layers
		(0 "F.Cu" signal)
		(1 "In1.Cu" signal)
		(2 "In2.Cu" signal)
		(3 "In3.Cu" signal)
		(4 "In4.Cu" jumper)
		(5 "In5.Cu" signal)
		(6 "In6.Cu" signal)
		(31 "B.Cu" signal)
		(32 "B.Adhes" user "B.Adhesive")
		(33 "F.Adhes" user "F.Adhesive")
		(34 "B.Paste" user)
		(35 "F.Paste" user)
		(36 "B.SilkS" user "B.Silkscreen")
		(37 "F.SilkS" user "F.Silkscreen")
		(38 "B.Mask" user)
		(39 "F.Mask" user)
		(40 "Dwgs.User" user "User.Drawings")
		(41 "Cmts.User" user "User.Comments")
		(42 "Eco1.User" user "User.Eco1")
		(43 "Eco2.User" user "User.Eco2")
		(44 "Edge.Cuts" user)
		(45 "Margin" user)
		(46 "B.CrtYd" user "B.Courtyard")
		(47 "F.CrtYd" user "F.Courtyard")
		(48 "B.Fab" user)
		(49 "F.Fab" user)
	)
	(footprint "antmicro-footprints:R_0402_1005Metric"
		(layer "F.Cu")
		(at 102.2 115.8 -90)
		(descr "Resistor SMD 0402")
		(tags "resistor SMD 0402")
		(property "Reference" "R139"
			(at -0.9 -0.45 -90)
			(layer "F.SilkS")
			(effects
				(font
					(size 0.7 0.7)
					(thickness 0.15)
				)
				(justify left bottom)
			)
		)
		(property "Value" "R_2k2_0402"
			(at 0 1.4 -90)
			(layer "F.Fab")
			(effects
				(font
					(size 0.7 0.7)
					(thickness 0.15)
				)
				(justify left bottom)
			)
		)
		(property "Footprint" "antmicro-footprints:R_0402_1005Metric"
			(at 0 0 -90)
			(layer "F.Fab")
			(hide yes)
			(effects
				(font
					(size 1.27 1.27)
					(thickness 0.15)
				)
			)
		)
		(property "Datasheet" "https://www.bourns.com/docs/product-datasheets/cr.pdf"
			(at 0 0 -90)
			(layer "F.Fab")
			(hide yes)
			(effects
				(font
					(size 1.27 1.27)
					(thickness 0.15)
				)
			)
		)
		(property "Author" "Antmicro"
			(at -13.6 218 0)
			(layer "F.Fab")
			(hide yes)
			(effects
				(font
					(size 1 1)
					(thickness 0.15)
				)
			)
		)
		(property "License" "Apache-2.0"
			(at -13.6 218 0)
			(layer "F.Fab")
			(hide yes)
			(effects
				(font
					(size 1 1)
					(thickness 0.15)
				)
			)
		)
		(property "MPN" "CR0402-FX-2201GLF"
			(at -13.6 218 0)
			(layer "F.Fab")
			(hide yes)
			(effects
				(font
					(size 1 1)
					(thickness 0.15)
				)
			)
		)
		(property "Manufacturer" "Bourns"
			(at -13.6 218 0)
			(layer "F.Fab")
			(hide yes)
			(effects
				(font
					(size 1 1)
					(thickness 0.15)
				)
			)
		)
		(property "Tolerance" "1%"
			(at -13.6 218 0)
			(layer "F.Fab")
			(hide yes)
			(effects
				(font
					(size 1 1)
					(thickness 0.15)
				)
			)
		)
		(property "Val" "2k2"
			(at -13.6 218 0)
			(layer "F.Fab")
			(hide yes)
			(effects
				(font
					(size 1 1)
					(thickness 0.15)
				)
			)
		)
		(sheetname "USB3")
		(sheetfile "usb3.kicad_sch")
		(attr smd)
		(fp_rect
			(start -0.925 -0.47)
			(end 0.925 0.47)
			(stroke
				(width 0.05)
				(type default)
			)
			(fill none)
			(layer "F.CrtYd")
		)
		(fp_rect
			(start -0.5 -0.25)
			(end 0.5 0.25)
			(stroke
				(width 0.15)
				(type solid)
			)
			(fill none)
			(layer "F.Fab")
		)
		(fp_text user "Author: Antmicro"
			(at -0.95 4.169 -90)
			(layer "F.Fab")
			(hide yes)
			(effects
				(font
					(size 0.7 0.7)
					(thickness 0.15)
				)
				(justify left bottom)
			)
		)
		(fp_text user "${REFERENCE}"
			(at -0.95 3.168 -90)
			(layer "F.Fab")
			(hide yes)
			(effects
				(font
					(size 0.7 0.7)
					(thickness 0.15)
				)
				(justify left bottom)
			)
		)
		(fp_text user "License: Apache-2.0"
			(at -0.95 5.169 -90)
			(layer "F.Fab")
			(hide yes)
			(effects
				(font
					(size 0.7 0.7)
					(thickness 0.15)
				)
				(justify left bottom)
			)
		)
		(pad "1" smd roundrect
			(at -0.48 0 270)
			(size 0.59 0.64)
			(layers "F.Cu" "F.Paste" "F.Mask")
			(roundrect_rratio 0.25)
			(net 1 "GND")
			(pintype "passive")
		)
		(pad "2" smd roundrect
			(at 0.48 0 270)
			(size 0.59 0.64)
			(layers "F.Cu" "F.Paste" "F.Mask")
			(roundrect_rratio 0.25)
			(net 564 "/USB3/USBC1_ISET")
			(pintype "passive")
		)
	)
	(footprint "antmicro-footprints:R_0603_1608Metric"
		(layer "F.Cu")
		(at 55.34 92.59)
		(descr "Resistor SMD 0603")
		(tags "resistor SMD 0603")
		(property "Reference" "R172"
			(at 27.17 1.445 0)
			(layer "F.SilkS")
			(effects
				(font
					(size 0.7 0.7)
					(thickness 0.15)
				)
				(justify left bottom)
			)
		)
		(property "Value" "R_0R_22.4A_0603"
			(at 0 1.6 0)
			(layer "F.Fab")
			(effects
				(font
					(size 0.7 0.7)
					(thickness 0.15)
				)
				(justify left bottom)
			)
		)
		(property "Footprint" "antmicro-footprints:R_0603_1608Metric"
			(at 0 0 0)
			(layer "F.Fab")
			(hide yes)
			(effects
				(font
					(size 1.27 1.27)
					(thickness 0.15)
				)
			)
		)
		(property "Datasheet" "https://fscdn.rohm.com/en/products/databook/datasheet/passive/resistor/chip_resistor/pmr-jpw-e.pdf"
			(at 0 0 0)
			(layer "F.Fab")
			(hide yes)
			(effects
				(font
					(size 1.27 1.27)
					(thickness 0.15)
				)
			)
		)
		(property "Author" "Antmicro"
			(at 147.35 36.79 90)
			(layer "F.Fab")
			(hide yes)
			(effects
				(font
					(size 1 1)
					(thickness 0.15)
				)
			)
		)
		(property "License" "Apache-2.0"
			(at 147.35 36.79 90)
			(layer "F.Fab")
			(hide yes)
			(effects
				(font
					(size 1 1)
					(thickness 0.15)
				)
			)
		)
		(property "MPN" "PMR03EZPJ000"
			(at 147.35 36.79 90)
			(layer "F.Fab")
			(hide yes)
			(effects
				(font
					(size 1 1)
					(thickness 0.15)
				)
			)
		)
		(property "Manufacturer" "ROHM Semiconductor"
			(at 147.35 36.79 90)
			(layer "F.Fab")
			(hide yes)
			(effects
				(font
					(size 1 1)
					(thickness 0.15)
				)
			)
		)
		(property "Max. Curr." "22.4A"
			(at 147.35 36.79 90)
			(layer "F.Fab")
			(hide yes)
			(effects
				(font
					(size 1 1)
					(thickness 0.15)
				)
			)
		)
		(property "Tolerance" "template_tolerance"
			(at 147.35 36.79 90)
			(layer "F.Fab")
			(hide yes)
			(effects
				(font
					(size 1 1)
					(thickness 0.15)
				)
			)
		)
		(property "Val" "0R"
			(at 147.35 36.79 90)
			(layer "F.Fab")
			(hide yes)
			(effects
				(font
					(size 1 1)
					(thickness 0.15)
				)
			)
		)
		(sheetname "Supply")
		(sheetfile "supply.kicad_sch")
		(attr smd)
		(fp_line
			(start -0.15 -0.4)
			(end 0.15 -0.4)
			(stroke
				(width 0.15)
				(type solid)
			)
			(layer "F.SilkS")
		)
		(fp_line
			(start -0.15 0.4)
			(end 0.15 0.4)
			(stroke
				(width 0.15)
				(type solid)
			)
			(layer "F.SilkS")
		)
		(fp_rect
			(start -1.25 -0.65)
			(end 1.25 0.65)
			(stroke
				(width 0.05)
				(type solid)
			)
			(fill none)
			(layer "F.CrtYd")
		)
		(fp_rect
			(start -0.8 -0.4)
			(end 0.8 0.4)
			(stroke
				(width 0.15)
				(type solid)
			)
			(fill none)
			(layer "F.Fab")
		)
		(fp_text user "${REFERENCE}"
			(at -1.25 3.898 0)
			(layer "F.Fab")
			(hide yes)
			(effects
				(font
					(size 0.7 0.7)
					(thickness 0.15)
				)
				(justify left bottom)
			)
		)
		(fp_text user "Author: Antmicro"
			(at -1.25 4.9 0)
			(layer "F.Fab")
			(hide yes)
			(effects
				(font
					(size 0.7 0.7)
					(thickness 0.15)
				)
				(justify left bottom)
			)
		)
		(fp_text user "License: Apache-2.0"
			(at -1.25 5.9 0)
			(layer "F.Fab")
			(hide yes)
			(effects
				(font
					(size 0.7 0.7)
					(thickness 0.15)
				)
				(justify left bottom)
			)
		)
		(pad "1" smd roundrect
			(at -0.7 0)
			(size 0.8 1)
			(layers "F.Cu" "F.Paste" "F.Mask")
			(roundrect_rratio 0.2)
			(net 761 "/Supply/5V_OUT")
			(pintype "passive")
		)
		(pad "2" smd roundrect
			(at 0.7 0)
			(size 0.8 1)
			(layers "F.Cu" "F.Paste" "F.Mask")
			(roundrect_rratio 0.2)
			(net 787 "+5V_SoM")
			(pintype "passive")
		)
	)
	(footprint "antmicro-footprints:XSON-8_1x1.95mm_P0.5mm"
		(layer "F.Cu")
		(at 56.9 105.1 180)
		(property "Reference" "U33"
			(at 1.025 1.25 0)
			(layer "F.SilkS")
			(effects
				(font
					(size 0.7 0.7)
					(thickness 0.15)
				)
				(justify left bottom)
			)
		)
		(property "Value" "NTS0102_XSON"
			(at 0 2.2 180)
			(layer "F.Fab")
			(effects
				(font
					(size 0.7 0.7)
					(thickness 0.15)
				)
				(justify left bottom)
			)
		)
		(property "Footprint" "antmicro-footprints:XSON-8_1x1.95mm_P0.5mm"
			(at 0 0 180)
			(layer "F.Fab")
			(hide yes)
			(effects
				(font
					(size 1.27 1.27)
					(thickness 0.15)
				)
			)
		)
		(property "Datasheet" "http://www.farnell.com/datasheets/1760723.pdf"
			(at 0 0 180)
			(layer "F.Fab")
			(hide yes)
			(effects
				(font
					(size 1.27 1.27)
					(thickness 0.15)
				)
			)
		)
		(property "Author" "Antmicro"
			(at 113.8 210.2 0)
			(layer "F.Fab")
			(hide yes)
			(effects
				(font
					(size 1 1)
					(thickness 0.15)
				)
			)
		)
		(property "License" "Apache-2.0"
			(at 113.8 210.2 0)
			(layer "F.Fab")
			(hide yes)
			(effects
				(font
					(size 1 1)
					(thickness 0.15)
				)
			)
		)
		(property "MPN" "NTS0102GT"
			(at 113.8 210.2 0)
			(layer "F.Fab")
			(hide yes)
			(effects
				(font
					(size 1 1)
					(thickness 0.15)
				)
			)
		)
		(property "Manufacturer" "NXP"
			(at 113.8 210.2 0)
			(layer "F.Fab")
			(hide yes)
			(effects
				(font
					(size 1 1)
					(thickness 0.15)
				)
			)
		)
		(sheetname "Peripherals")
		(sheetfile "peripherals.kicad_sch")
		(attr smd)
		(fp_line
			(start 0.5 1.1)
			(end -0.5 1.1)
			(stroke
				(width 0.15)
				(type solid)
			)
			(layer "F.SilkS")
		)
		(fp_line
			(start -0.5 -1.1)
			(end 0.5 -1.1)
			(stroke
				(width 0.15)
				(type solid)
			)
			(layer "F.SilkS")
		)
		(fp_circle
			(center -0.75 -1.1)
			(end -0.701 -1.1)
			(stroke
				(width 0.15)
				(type solid)
			)
			(fill none)
			(layer "F.SilkS")
		)
		(fp_rect
			(start -0.8 -1.2)
			(end 0.8 1.2)
			(stroke
				(width 0.05)
				(type solid)
			)
			(fill none)
			(layer "F.CrtYd")
		)
		(fp_line
			(start 0.5305 1)
			(end -0.5305 1)
			(stroke
				(width 0.15)
				(type solid)
			)
			(layer "F.Fab")
		)
		(fp_line
			(start 0.5305 -1.001)
			(end 0.5305 1)
			(stroke
				(width 0.15)
				(type solid)
			)
			(layer "F.Fab")
		)
		(fp_line
			(start -0.5305 1)
			(end -0.5305 -1.001)
			(stroke
				(width 0.15)
				(type solid)
			)
			(layer "F.Fab")
		)
		(fp_line
			(start -0.5305 -1.001)
			(end 0.5305 -1.001)
			(stroke
				(width 0.15)
				(type solid)
			)
			(layer "F.Fab")
		)
		(fp_text user "Author: Antmicro"
			(at -0.527 7.105 180)
			(layer "F.Fab")
			(hide yes)
			(effects
				(font
					(size 0.7 0.7)
					(thickness 0.15)
				)
				(justify left bottom)
			)
		)
		(fp_text user "${REFERENCE}"
			(at -0.527 5.905 180)
			(layer "F.Fab")
			(hide yes)
			(effects
				(font
					(size 0.7 0.7)
					(thickness 0.15)
				)
				(justify left bottom)
			)
		)
		(fp_text user "License: Apache-2.0"
			(at -0.527 8.306 180)
			(layer "F.Fab")
			(hide yes)
			(effects
				(font
					(size 0.7 0.7)
					(thickness 0.15)
				)
				(justify left bottom)
			)
		)
		(pad "1" smd roundrect
			(at -0.45 -0.75)
			(size 0.6 0.3)
			(layers "F.Cu" "F.Paste" "F.Mask")
			(roundrect_rratio 0.25)
			(net 541 "/Peripherals/FAN_TACH_5V")
			(pinfunction "B_{2}")
			(pintype "bidirectional")
		)
		(pad "2" smd roundrect
			(at -0.45 -0.25)
			(size 0.6 0.25)
			(layers "F.Cu" "F.Paste" "F.Mask")
			(roundrect_rratio 0.25)
			(net 1 "GND")
			(pinfunction "GND")
			(pintype "power_in")
		)
		(pad "3" smd roundrect
			(at -0.45 0.25)
			(size 0.6 0.25)
			(layers "F.Cu" "F.Paste" "F.Mask")
			(roundrect_rratio 0.25)
			(net 112 "+1V8")
			(pinfunction "VCC_{A}")
			(pintype "power_in")
		)
		(pad "4" smd roundrect
			(at -0.45 0.75)
			(size 0.6 0.3)
			(layers "F.Cu" "F.Paste" "F.Mask")
			(roundrect_rratio 0.25)
			(net 463 "FAN_TACH")
			(pinfunction "A_{2}")
			(pintype "bidirectional")
		)
		(pad "5" smd roundrect
			(at 0.45 0.75)
			(size 0.6 0.3)
			(layers "F.Cu" "F.Paste" "F.Mask")
			(roundrect_rratio 0.25)
			(net 473 "FAN_PWM")
			(pinfunction "A_{1}")
			(pintype "bidirectional")
		)
		(pad "6" smd roundrect
			(at 0.45 0.25)
			(size 0.6 0.25)
			(layers "F.Cu" "F.Paste" "F.Mask")
			(roundrect_rratio 0.25)
			(net 112 "+1V8")
			(pinfunction "OE")
			(pintype "input")
		)
		(pad "7" smd roundrect
			(at 0.45 -0.25)
			(size 0.6 0.25)
			(layers "F.Cu" "F.Paste" "F.Mask")
			(roundrect_rratio 0.25)
			(net 99 "+5V")
			(pinfunction "VCC_{B}")
			(pintype "power_in")
		)
		(pad "8" smd roundrect
			(at 0.45 -0.75)
			(size 0.6 0.3)
			(layers "F.Cu" "F.Paste" "F.Mask")
			(roundrect_rratio 0.25)
			(net 540 "/Peripherals/FAN_PWM_5V")
			(pinfunction "B_{1}")
			(pintype "bidirectional")
		)
	)
	(footprint "antmicro-footprints:C_0402_1005Metric"
		(layer "F.Cu")
		(at 136.35 87.25 180)
		(descr "Capacitor SMD 0402")
		(tags "capacitor SMD 0402")
		(property "Reference" "C109"
			(at 3.65 -0.45 180)
			(layer "F.SilkS")
			(effects
				(font
					(size 0.7 0.7)
					(thickness 0.15)
				)
				(justify left bottom)
			)
		)
		(property "Value" "C_220n_0402"
			(at 0 1.4 180)
			(layer "F.Fab")
			(effects
				(font
					(size 0.7 0.7)
					(thickness 0.15)
				)
				(justify left bottom)
			)
		)
		(property "Footprint" "antmicro-footprints:C_0402_1005Metric"
			(at 0 0 180)
			(layer "F.Fab")
			(hide yes)
			(effects
				(font
					(size 1.27 1.27)
					(thickness 0.15)
				)
			)
		)
		(property "Datasheet" "https://www.yageo.com/en/Chart/Download/pdf/CC0402KRX5R6BB224"
			(at 0 0 180)
			(layer "F.Fab")
			(hide yes)
			(effects
				(font
					(size 1.27 1.27)
					(thickness 0.15)
				)
			)
		)
		(property "Author" "Antmicro"
			(at 272.7 174.5 0)
			(layer "F.Fab")
			(hide yes)
			(effects
				(font
					(size 1 1)
					(thickness 0.15)
				)
			)
		)
		(property "Dielectric" ""
			(at 272.7 174.5 0)
			(layer "F.Fab")
			(hide yes)
			(effects
				(font
					(size 1 1)
					(thickness 0.15)
				)
			)
		)
		(property "License" "Apache-2.0"
			(at 272.7 174.5 0)
			(layer "F.Fab")
			(hide yes)
			(effects
				(font
					(size 1 1)
					(thickness 0.15)
				)
			)
		)
		(property "MPN" "CC0402KRX5R6BB224"
			(at 272.7 174.5 0)
			(layer "F.Fab")
			(hide yes)
			(effects
				(font
					(size 1 1)
					(thickness 0.15)
				)
			)
		)
		(property "Manufacturer" "YAGEO"
			(at 272.7 174.5 0)
			(layer "F.Fab")
			(hide yes)
			(effects
				(font
					(size 1 1)
					(thickness 0.15)
				)
			)
		)
		(property "Val" "220n"
			(at 272.7 174.5 0)
			(layer "F.Fab")
			(hide yes)
			(effects
				(font
					(size 1 1)
					(thickness 0.15)
				)
			)
		)
		(property "Voltage" ""
			(at 272.7 174.5 0)
			(layer "F.Fab")
			(hide yes)
			(effects
				(font
					(size 1 1)
					(thickness 0.15)
				)
			)
		)
		(sheetname "Peripherals")
		(sheetfile "peripherals.kicad_sch")
		(attr smd)
		(fp_rect
			(start -0.925 -0.47)
			(end 0.925 0.47)
			(stroke
				(width 0.05)
				(type default)
			)
			(fill none)
			(layer "F.CrtYd")
		)
		(fp_line
			(start 0.504 0.248)
			(end -0.494 0.248)
			(stroke
				(width 0.15)
				(type solid)
			)
			(layer "F.Fab")
		)
		(fp_line
			(start 0.504 -0.25)
			(end 0.504 0.248)
			(stroke
				(width 0.15)
				(type solid)
			)
			(layer "F.Fab")
		)
		(fp_line
			(start -0.494 0.248)
			(end -0.494 -0.25)
			(stroke
				(width 0.15)
				(type solid)
			)
			(layer "F.Fab")
		)
		(fp_line
			(start -0.494 -0.25)
			(end 0.504 -0.25)
			(stroke
				(width 0.15)
				(type solid)
			)
			(layer "F.Fab")
		)
		(fp_text user "${REFERENCE}"
			(at -0.932 3.168 180)
			(layer "F.Fab")
			(hide yes)
			(effects
				(font
					(size 0.7 0.7)
					(thickness 0.15)
				)
				(justify left bottom)
			)
		)
		(fp_text user "Author: Antmicro"
			(at -0.932 4.17 180)
			(layer "F.Fab")
			(hide yes)
			(effects
				(font
					(size 0.7 0.7)
					(thickness 0.15)
				)
				(justify left bottom)
			)
		)
		(fp_text user "License: Apache-2.0"
			(at -0.932 5.17 180)
			(layer "F.Fab")
			(hide yes)
			(effects
				(font
					(size 0.7 0.7)
					(thickness 0.15)
				)
				(justify left bottom)
			)
		)
		(pad "1" smd roundrect
			(at -0.48 0 180)
			(size 0.59 0.64)
			(layers "F.Cu" "F.Paste" "F.Mask")
			(roundrect_rratio 0.25)
			(net 412 "/Peripherals/PCIE2_TX0_CONN_P")
			(pintype "passive")
		)
		(pad "2" smd roundrect
			(at 0.48 0 180)
			(size 0.59 0.64)
			(layers "F.Cu" "F.Paste" "F.Mask")
			(roundrect_rratio 0.25)
			(net 158 "PCIE2_TX0_P")
			(pintype "passive")
		)
	)
)
